# S9S_MB_2U (Grand Teton) — schematic netlist excerpt (pin names and nets, part order shuffled) for the footprints in the layout excerpt that follows; sources: Cadence DE-HDL packaged netlist, KiCad conversion of 03242023_DA0F0TMBIJ0_F0T_Motherboard_J_brd_V01_OCP.brd

PC2200  Q_CAP  1UF 25V 10% EMPTY  pkg C0402  page 193 : A = P3V3_AUX ; B = GND
R3086  Q_RES  130 1% CHIP  pkg 0402LF  page 253 : A = LED_PWRGD_PVCCD_HV_CPU0 ; B = P3V3_AUX

(kicad_pcb
	(version 20260206)
	(generator "pcbnew")
	(generator_version "10.0")
	(general
		(thickness 1.6)
		(legacy_teardrops no)
	)
	(paper "A4")
	(title_block
		(title "03242023_DA0F0TMBIJ0_F0T_Motherboard_J_brd_V01_OCP.brd")
		(comment 1 "Grand Teton / footprints 1355-1356 of 6105")
	)
	(layers
		(0 "F.Cu" signal "TOP")
		(4 "In1.Cu" signal "GND")
		(6 "In2.Cu" signal "IN1")
		(8 "In3.Cu" signal "GND1")
		(10 "In4.Cu" signal "IN2")
		(12 "In5.Cu" signal "GND2")
		(14 "In6.Cu" signal "IN3")
		(16 "In7.Cu" signal "GND3")
		(18 "In8.Cu" signal "VCC")
		(20 "In9.Cu" signal "VCC1")
		(22 "In10.Cu" signal "GND4")
		(24 "In11.Cu" signal "IN4")
		(26 "In12.Cu" signal "GND5")
		(28 "In13.Cu" signal "IN5")
		(30 "In14.Cu" signal "GND6")
		(32 "In15.Cu" signal "IN6")
		(34 "In16.Cu" signal "GND7")
		(2 "B.Cu" signal "BOTTOM")
		(9 "F.Adhes" user "F.Adhesive")
		(11 "B.Adhes" user "B.Adhesive")
		(13 "F.Paste" user "Package Geometry/Pastemask Top")
		(15 "B.Paste" user "Package Geometry/Pastemask Bottom")
		(5 "F.SilkS" user "Ref Des/Silkscreen Top")
		(7 "B.SilkS" user "Ref Des/Silkscreen Bottom")
		(1 "F.Mask" user "Board Geometry/Soldermask Top")
		(3 "B.Mask" user "Board Geometry/Soldermask Bottom")
		(17 "Dwgs.User" user "User.Drawings")
		(19 "Cmts.User" user "User.Comments")
		(21 "Eco1.User" user "User.Eco1")
		(23 "Eco2.User" user "User.Eco2")
		(25 "Edge.Cuts" user "Board Geometry/Outline")
		(27 "Margin" user)
		(31 "F.CrtYd" user "Package Geometry/Place Bound Top")
		(29 "B.CrtYd" user "Package Geometry/Place Bound Bottom")
		(35 "F.Fab" user "Ref Des/Assembly Top")
		(33 "B.Fab" user "Ref Des/Assembly Bottom")
	)
	(footprint ""
		(layer "F.Cu")
		(at 83.566508 -74.901552 -90)
		(property "Reference" "R3086"
			(at 0 0 270)
			(layer "F.SilkS")
			(hide yes)
			(effects
				(font
					(size 1.27 1.27)
				)
			)
		)
		(property "Value" ""
			(at 0 0 270)
			(layer "F.Fab")
			(effects
				(font
					(size 1.27 1.27)
				)
			)
		)
		(duplicate_pad_numbers_are_jumpers no)
		(fp_line
			(start -0.7874 0.4064)
			(end -0.7874 -0.4064)
			(stroke
				(width 0.1524)
				(type default)
			)
			(layer "F.SilkS")
		)
		(fp_line
			(start 0.7874 0.4064)
			(end -0.7874 0.4064)
			(stroke
				(width 0.1524)
				(type default)
			)
			(layer "F.SilkS")
		)
		(fp_line
			(start -0.7874 -0.4064)
			(end 0.7874 -0.4064)
			(stroke
				(width 0.1524)
				(type default)
			)
			(layer "F.SilkS")
		)
		(fp_line
			(start 0.7874 -0.4064)
			(end 0.7874 0.4064)
			(stroke
				(width 0.1524)
				(type default)
			)
			(layer "F.SilkS")
		)
		(fp_line
			(start -0.67945 0.3048)
			(end -0.67945 -0.305054)
			(stroke
				(width 0.1)
				(type default)
			)
			(layer "F.Fab")
		)
		(fp_line
			(start -0.12065 0.3048)
			(end -0.67945 0.3048)
			(stroke
				(width 0.1)
				(type default)
			)
			(layer "F.Fab")
		)
		(fp_line
			(start 0.120396 0.3048)
			(end 0.120396 0.2794)
			(stroke
				(width 0.1)
				(type default)
			)
			(layer "F.Fab")
		)
		(fp_line
			(start 0.67945 0.3048)
			(end 0.120396 0.3048)
			(stroke
				(width 0.1)
				(type default)
			)
			(layer "F.Fab")
		)
		(fp_line
			(start -0.12065 0.2794)
			(end -0.12065 0.3048)
			(stroke
				(width 0.1)
				(type default)
			)
			(layer "F.Fab")
		)
		(fp_line
			(start 0.120396 0.2794)
			(end -0.12065 0.2794)
			(stroke
				(width 0.1)
				(type default)
			)
			(layer "F.Fab")
		)
		(fp_line
			(start -0.12065 -0.2794)
			(end 0.12065 -0.2794)
			(stroke
				(width 0.1)
				(type default)
			)
			(layer "F.Fab")
		)
		(fp_line
			(start 0.12065 -0.2794)
			(end 0.12065 -0.3048)
			(stroke
				(width 0.1)
				(type default)
			)
			(layer "F.Fab")
		)
		(fp_line
			(start 0.12065 -0.3048)
			(end 0.67945 -0.3048)
			(stroke
				(width 0.1)
				(type default)
			)
			(layer "F.Fab")
		)
		(fp_line
			(start 0.67945 -0.3048)
			(end 0.67945 0.3048)
			(stroke
				(width 0.1)
				(type default)
			)
			(layer "F.Fab")
		)
		(fp_line
			(start -0.67945 -0.305054)
			(end -0.12065 -0.305054)
			(stroke
				(width 0.1)
				(type default)
			)
			(layer "F.Fab")
		)
		(fp_line
			(start -0.12065 -0.305054)
			(end -0.12065 -0.2794)
			(stroke
				(width 0.1)
				(type default)
			)
			(layer "F.Fab")
		)
		(pad "1" smd circle
			(at -0.40005 0 270)
			(size 0 0)
			(layers "F.Cu" "F.Mask" "F.Paste")
			(net "LED_PWRGD_PVCCD_HV_CPU0")
		)
		(pad "2" smd circle
			(at 0.40005 0 270)
			(size 0 0)
			(layers "F.Cu" "F.Mask" "F.Paste")
			(net "P3V3_AUX")
		)
	)
	(footprint ""
		(layer "F.Cu")
		(at 194.35064 -71.836788 90)
		(property "Reference" "PC2200"
			(at 0 0 90)
			(layer "F.SilkS")
			(hide yes)
			(effects
				(font
					(size 1.27 1.27)
				)
			)
		)
		(property "Value" ""
			(at 0 0 90)
			(layer "F.Fab")
			(effects
				(font
					(size 1.27 1.27)
				)
			)
		)
		(duplicate_pad_numbers_are_jumpers no)
		(fp_line
			(start 0.7874 -0.4064)
			(end 0.7874 0.4064)
			(stroke
				(width 0.1524)
				(type default)
			)
			(layer "F.SilkS")
		)
		(fp_line
			(start -0.7874 -0.4064)
			(end 0.7874 -0.4064)
			(stroke
				(width 0.1524)
				(type default)
			)
			(layer "F.SilkS")
		)
		(fp_line
			(start 0.7874 0.4064)
			(end -0.7874 0.4064)
			(stroke
				(width 0.1524)
				(type default)
			)
			(layer "F.SilkS")
		)
		(fp_line
			(start -0.7874 0.4064)
			(end -0.7874 -0.4064)
			(stroke
				(width 0.1524)
				(type default)
			)
			(layer "F.SilkS")
		)
		(fp_line
			(start -0.12065 -0.305054)
			(end -0.12065 -0.2794)
			(stroke
				(width 0.1)
				(type default)
			)
			(layer "F.Fab")
		)
		(fp_line
			(start -0.67945 -0.305054)
			(end -0.12065 -0.305054)
			(stroke
				(width 0.1)
				(type default)
			)
			(layer "F.Fab")
		)
		(fp_line
			(start 0.67945 -0.3048)
			(end 0.67945 0.3048)
			(stroke
				(width 0.1)
				(type default)
			)
			(layer "F.Fab")
		)
		(fp_line
			(start 0.12065 -0.3048)
			(end 0.67945 -0.3048)
			(stroke
				(width 0.1)
				(type default)
			)
			(layer "F.Fab")
		)
		(fp_line
			(start 0.12065 -0.2794)
			(end 0.12065 -0.3048)
			(stroke
				(width 0.1)
				(type default)
			)
			(layer "F.Fab")
		)
		(fp_line
			(start -0.12065 -0.2794)
			(end 0.12065 -0.2794)
			(stroke
				(width 0.1)
				(type default)
			)
			(layer "F.Fab")
		)
		(fp_line
			(start 0.120396 0.2794)
			(end -0.12065 0.2794)
			(stroke
				(width 0.1)
				(type default)
			)
			(layer "F.Fab")
		)
		(fp_line
			(start -0.12065 0.2794)
			(end -0.12065 0.3048)
			(stroke
				(width 0.1)
				(type default)
			)
			(layer "F.Fab")
		)
		(fp_line
			(start 0.67945 0.3048)
			(end 0.120396 0.3048)
			(stroke
				(width 0.1)
				(type default)
			)
			(layer "F.Fab")
		)
		(fp_line
			(start 0.120396 0.3048)
			(end 0.120396 0.2794)
			(stroke
				(width 0.1)
				(type default)
			)
			(layer "F.Fab")
		)
		(fp_line
			(start -0.12065 0.3048)
			(end -0.67945 0.3048)
			(stroke
				(width 0.1)
				(type default)
			)
			(layer "F.Fab")
		)
		(fp_line
			(start -0.67945 0.3048)
			(end -0.67945 -0.305054)
			(stroke
				(width 0.1)
				(type default)
			)
			(layer "F.Fab")
		)
		(pad "1" smd circle
			(at -0.40005 0 90)
			(size 0 0)
			(layers "F.Cu" "F.Mask" "F.Paste")
			(net "P3V3_AUX")
		)
		(pad "2" smd circle
			(at 0.40005 0 90)
			(size 0 0)
			(layers "F.Cu" "F.Mask" "F.Paste")
			(net "GND")
		)
	)
)
